(kicad_pcb
	(version 20260206)
	(generator "pcbnew")
	(generator_version "10.0")
	(general
		(thickness 1.6)
		(legacy_teardrops no)
	)
	(paper "A4")
	(title_block
		(title "03242023_DA0F0TMBIJ0_F0T_Motherboard_J_brd_V01_OCP.brd")
		(comment 1 "Grand Teton / footprints 4791-4796 of 6105")
	)
	(layers
		(0 "F.Cu" signal "TOP")
		(4 "In1.Cu" signal "GND")
		(6 "In2.Cu" signal "IN1")
		(8 "In3.Cu" signal "GND1")
		(10 "In4.Cu" signal "IN2")
		(12 "In5.Cu" signal "GND2")
		(14 "In6.Cu" signal "IN3")
		(16 "In7.Cu" signal "GND3")
		(18 "In8.Cu" signal "VCC")
		(20 "In9.Cu" signal "VCC1")
		(22 "In10.Cu" signal "GND4")
		(24 "In11.Cu" signal "IN4")
		(26 "In12.Cu" signal "GND5")
		(28 "In13.Cu" signal "IN5")
		(30 "In14.Cu" signal "GND6")
		(32 "In15.Cu" signal "IN6")
		(34 "In16.Cu" signal "GND7")
		(2 "B.Cu" signal "BOTTOM")
		(9 "F.Adhes" user "F.Adhesive")
		(11 "B.Adhes" user "B.Adhesive")
		(13 "F.Paste" user "Package Geometry/Pastemask Top")
		(15 "B.Paste" user "Package Geometry/Pastemask Bottom")
		(5 "F.SilkS" user "Ref Des/Silkscreen Top")
		(7 "B.SilkS" user "Ref Des/Silkscreen Bottom")
		(1 "F.Mask" user "Board Geometry/Soldermask Top")
		(3 "B.Mask" user "Board Geometry/Soldermask Bottom")
		(17 "Dwgs.User" user "User.Drawings")
		(19 "Cmts.User" user "User.Comments")
		(21 "Eco1.User" user "User.Eco1")
		(23 "Eco2.User" user "User.Eco2")
		(25 "Edge.Cuts" user "Board Geometry/Outline")
		(27 "Margin" user)
		(31 "F.CrtYd" user "Package Geometry/Place Bound Top")
		(29 "B.CrtYd" user "Package Geometry/Place Bound Bottom")
		(35 "F.Fab" user "Ref Des/Assembly Top")
		(33 "B.Fab" user "Ref Des/Assembly Bottom")
	)
	(footprint ""
		(layer "B.Cu")
		(at 180.90388 -329.479148 180)
		(property "Reference" "R1932"
			(at 0 0 0)
			(layer "B.SilkS")
			(hide yes)
			(effects
				(font
					(size 1.27 1.27)
				)
				(justify mirror)
			)
		)
		(property "Value" ""
			(at 0 0 0)
			(layer "B.Fab")
			(effects
				(font
					(size 1.27 1.27)
				)
				(justify mirror)
			)
		)
		(duplicate_pad_numbers_are_jumpers no)
		(fp_line
			(start 0.7874 0.4064)
			(end 0.7874 -0.4064)
			(stroke
				(width 0.1524)
				(type default)
			)
			(layer "B.SilkS")
		)
		(fp_line
			(start 0.7874 -0.4064)
			(end -0.7874 -0.4064)
			(stroke
				(width 0.1524)
				(type default)
			)
			(layer "B.SilkS")
		)
		(fp_line
			(start -0.7874 0.4064)
			(end 0.7874 0.4064)
			(stroke
				(width 0.1524)
				(type default)
			)
			(layer "B.SilkS")
		)
		(fp_line
			(start -0.7874 -0.4064)
			(end -0.7874 0.4064)
			(stroke
				(width 0.1524)
				(type default)
			)
			(layer "B.SilkS")
		)
		(fp_line
			(start 0.67945 0.3048)
			(end 0.67945 -0.305054)
			(stroke
				(width 0.1)
				(type default)
			)
			(layer "B.Fab")
		)
		(fp_line
			(start 0.67945 -0.305054)
			(end 0.12065 -0.305054)
			(stroke
				(width 0.1)
				(type default)
			)
			(layer "B.Fab")
		)
		(fp_line
			(start 0.12065 0.3048)
			(end 0.67945 0.3048)
			(stroke
				(width 0.1)
				(type default)
			)
			(layer "B.Fab")
		)
		(fp_line
			(start 0.12065 0.2794)
			(end 0.12065 0.3048)
			(stroke
				(width 0.1)
				(type default)
			)
			(layer "B.Fab")
		)
		(fp_line
			(start 0.12065 -0.2794)
			(end -0.12065 -0.2794)
			(stroke
				(width 0.1)
				(type default)
			)
			(layer "B.Fab")
		)
		(fp_line
			(start 0.12065 -0.305054)
			(end 0.12065 -0.2794)
			(stroke
				(width 0.1)
				(type default)
			)
			(layer "B.Fab")
		)
		(fp_line
			(start -0.120396 0.3048)
			(end -0.120396 0.2794)
			(stroke
				(width 0.1)
				(type default)
			)
			(layer "B.Fab")
		)
		(fp_line
			(start -0.120396 0.2794)
			(end 0.12065 0.2794)
			(stroke
				(width 0.1)
				(type default)
			)
			(layer "B.Fab")
		)
		(fp_line
			(start -0.12065 -0.2794)
			(end -0.12065 -0.3048)
			(stroke
				(width 0.1)
				(type default)
			)
			(layer "B.Fab")
		)
		(fp_line
			(start -0.12065 -0.3048)
			(end -0.67945 -0.3048)
			(stroke
				(width 0.1)
				(type default)
			)
			(layer "B.Fab")
		)
		(fp_line
			(start -0.67945 0.3048)
			(end -0.120396 0.3048)
			(stroke
				(width 0.1)
				(type default)
			)
			(layer "B.Fab")
		)
		(fp_line
			(start -0.67945 -0.3048)
			(end -0.67945 0.3048)
			(stroke
				(width 0.1)
				(type default)
			)
			(layer "B.Fab")
		)
		(pad "1" smd circle
			(at 0.40005 0)
			(size 0 0)
			(layers "B.Cu" "B.Mask" "B.Paste")
			(net "SMB_S3M_CPU0_PIROM_3V3AUX_SCL")
		)
		(pad "2" smd circle
			(at -0.40005 0)
			(size 0 0)
			(layers "B.Cu" "B.Mask" "B.Paste")
			(net "SMB_S3M_CPU0_PIROM_3V3AUX_SCL_1")
		)
	)
	(footprint ""
		(layer "B.Cu")
		(at 336.494882 -187.387738 180)
		(property "Reference" "R687"
			(at 0 0 0)
			(layer "B.SilkS")
			(hide yes)
			(effects
				(font
					(size 1.27 1.27)
				)
				(justify mirror)
			)
		)
		(property "Value" ""
			(at 0 0 0)
			(layer "B.Fab")
			(effects
				(font
					(size 1.27 1.27)
				)
				(justify mirror)
			)
		)
		(duplicate_pad_numbers_are_jumpers no)
		(fp_line
			(start 0.7874 0.4064)
			(end 0.7874 -0.4064)
			(stroke
				(width 0.1524)
				(type default)
			)
			(layer "B.SilkS")
		)
		(fp_line
			(start 0.7874 -0.4064)
			(end -0.7874 -0.4064)
			(stroke
				(width 0.1524)
				(type default)
			)
			(layer "B.SilkS")
		)
		(fp_line
			(start -0.7874 0.4064)
			(end 0.7874 0.4064)
			(stroke
				(width 0.1524)
				(type default)
			)
			(layer "B.SilkS")
		)
		(fp_line
			(start -0.7874 -0.4064)
			(end -0.7874 0.4064)
			(stroke
				(width 0.1524)
				(type default)
			)
			(layer "B.SilkS")
		)
		(fp_line
			(start 0.67945 0.3048)
			(end 0.67945 -0.305054)
			(stroke
				(width 0.1)
				(type default)
			)
			(layer "B.Fab")
		)
		(fp_line
			(start 0.67945 -0.305054)
			(end 0.12065 -0.305054)
			(stroke
				(width 0.1)
				(type default)
			)
			(layer "B.Fab")
		)
		(fp_line
			(start 0.12065 0.3048)
			(end 0.67945 0.3048)
			(stroke
				(width 0.1)
				(type default)
			)
			(layer "B.Fab")
		)
		(fp_line
			(start 0.12065 0.2794)
			(end 0.12065 0.3048)
			(stroke
				(width 0.1)
				(type default)
			)
			(layer "B.Fab")
		)
		(fp_line
			(start 0.12065 -0.2794)
			(end -0.12065 -0.2794)
			(stroke
				(width 0.1)
				(type default)
			)
			(layer "B.Fab")
		)
		(fp_line
			(start 0.12065 -0.305054)
			(end 0.12065 -0.2794)
			(stroke
				(width 0.1)
				(type default)
			)
			(layer "B.Fab")
		)
		(fp_line
			(start -0.120396 0.3048)
			(end -0.120396 0.2794)
			(stroke
				(width 0.1)
				(type default)
			)
			(layer "B.Fab")
		)
		(fp_line
			(start -0.120396 0.2794)
			(end 0.12065 0.2794)
			(stroke
				(width 0.1)
				(type default)
			)
			(layer "B.Fab")
		)
		(fp_line
			(start -0.12065 -0.2794)
			(end -0.12065 -0.3048)
			(stroke
				(width 0.1)
				(type default)
			)
			(layer "B.Fab")
		)
		(fp_line
			(start -0.12065 -0.3048)
			(end -0.67945 -0.3048)
			(stroke
				(width 0.1)
				(type default)
			)
			(layer "B.Fab")
		)
		(fp_line
			(start -0.67945 0.3048)
			(end -0.120396 0.3048)
			(stroke
				(width 0.1)
				(type default)
			)
			(layer "B.Fab")
		)
		(fp_line
			(start -0.67945 -0.3048)
			(end -0.67945 0.3048)
			(stroke
				(width 0.1)
				(type default)
			)
			(layer "B.Fab")
		)
		(pad "1" smd circle
			(at 0.40005 0)
			(size 0 0)
			(layers "B.Cu" "B.Mask" "B.Paste")
			(net "I3C_SPD_DDRABCD_CPU0_SCL")
		)
		(pad "2" smd circle
			(at -0.40005 0)
			(size 0 0)
			(layers "B.Cu" "B.Mask" "B.Paste")
			(net "I3C_SPD_DDRABCD_CPU0_R_SCL")
		)
	)
	(footprint ""
		(layer "B.Cu")
		(at 162.95624 -250.300236 90)
		(property "Reference" "C485"
			(at 0 0 90)
			(layer "B.SilkS")
			(hide yes)
			(effects
				(font
					(size 1.27 1.27)
				)
				(justify mirror)
			)
		)
		(property "Value" ""
			(at 0 0 90)
			(layer "B.Fab")
			(effects
				(font
					(size 1.27 1.27)
				)
				(justify mirror)
			)
		)
		(duplicate_pad_numbers_are_jumpers no)
		(fp_line
			(start 1.524 -0.762)
			(end -1.524 -0.762)
			(stroke
				(width 0.1524)
				(type default)
			)
			(layer "B.SilkS")
		)
		(fp_line
			(start -1.524 -0.762)
			(end -1.524 0.762)
			(stroke
				(width 0.1524)
				(type default)
			)
			(layer "B.SilkS")
		)
		(fp_line
			(start 1.524 0.762)
			(end 1.524 -0.762)
			(stroke
				(width 0.1524)
				(type default)
			)
			(layer "B.SilkS")
		)
		(fp_line
			(start -1.524 0.762)
			(end 1.524 0.762)
			(stroke
				(width 0.1524)
				(type default)
			)
			(layer "B.SilkS")
		)
		(fp_line
			(start 1.1049 -0.724916)
			(end 1.1049 0.724916)
			(stroke
				(width 0.1)
				(type default)
			)
			(layer "B.Fab")
		)
		(fp_line
			(start -1.1049 -0.724916)
			(end 1.1049 -0.724916)
			(stroke
				(width 0.1)
				(type default)
			)
			(layer "B.Fab")
		)
		(fp_line
			(start 1.1049 0.724916)
			(end -1.1049 0.724916)
			(stroke
				(width 0.1)
				(type default)
			)
			(layer "B.Fab")
		)
		(fp_line
			(start -1.1049 0.724916)
			(end -1.1049 -0.724916)
			(stroke
				(width 0.1)
				(type default)
			)
			(layer "B.Fab")
		)
		(pad "1" smd rect
			(at 0.889 0 90)
			(size 1.016 1.27)
			(layers "B.Cu" "B.Mask" "B.Paste")
			(net "PVCCFA_EHV_FIVRA_CPU1")
		)
		(pad "2" smd rect
			(at -0.889 0 90)
			(size 1.016 1.27)
			(layers "B.Cu" "B.Mask" "B.Paste")
			(net "GND")
		)
	)
	(footprint ""
		(layer "B.Cu")
		(at 94.209108 -190.705232 -90)
		(property "Reference" "R663"
			(at 0 0 90)
			(layer "B.SilkS")
			(hide yes)
			(effects
				(font
					(size 1.27 1.27)
				)
				(justify mirror)
			)
		)
		(property "Value" ""
			(at 0 0 90)
			(layer "B.Fab")
			(effects
				(font
					(size 1.27 1.27)
				)
				(justify mirror)
			)
		)
		(duplicate_pad_numbers_are_jumpers no)
		(fp_line
			(start -0.7874 0.4064)
			(end 0.7874 0.4064)
			(stroke
				(width 0.1524)
				(type default)
			)
			(layer "B.SilkS")
		)
		(fp_line
			(start 0.7874 0.4064)
			(end 0.7874 -0.4064)
			(stroke
				(width 0.1524)
				(type default)
			)
			(layer "B.SilkS")
		)
		(fp_line
			(start -0.7874 -0.4064)
			(end -0.7874 0.4064)
			(stroke
				(width 0.1524)
				(type default)
			)
			(layer "B.SilkS")
		)
		(fp_line
			(start 0.7874 -0.4064)
			(end -0.7874 -0.4064)
			(stroke
				(width 0.1524)
				(type default)
			)
			(layer "B.SilkS")
		)
		(fp_line
			(start -0.67945 0.3048)
			(end -0.120396 0.3048)
			(stroke
				(width 0.1)
				(type default)
			)
			(layer "B.Fab")
		)
		(fp_line
			(start -0.120396 0.3048)
			(end -0.120396 0.2794)
			(stroke
				(width 0.1)
				(type default)
			)
			(layer "B.Fab")
		)
		(fp_line
			(start 0.12065 0.3048)
			(end 0.67945 0.3048)
			(stroke
				(width 0.1)
				(type default)
			)
			(layer "B.Fab")
		)
		(fp_line
			(start 0.67945 0.3048)
			(end 0.67945 -0.305054)
			(stroke
				(width 0.1)
				(type default)
			)
			(layer "B.Fab")
		)
		(fp_line
			(start -0.120396 0.2794)
			(end 0.12065 0.2794)
			(stroke
				(width 0.1)
				(type default)
			)
			(layer "B.Fab")
		)
		(fp_line
			(start 0.12065 0.2794)
			(end 0.12065 0.3048)
			(stroke
				(width 0.1)
				(type default)
			)
			(layer "B.Fab")
		)
		(fp_line
			(start -0.12065 -0.2794)
			(end -0.12065 -0.3048)
			(stroke
				(width 0.1)
				(type default)
			)
			(layer "B.Fab")
		)
		(fp_line
			(start 0.12065 -0.2794)
			(end -0.12065 -0.2794)
			(stroke
				(width 0.1)
				(type default)
			)
			(layer "B.Fab")
		)
		(fp_line
			(start -0.67945 -0.3048)
			(end -0.67945 0.3048)
			(stroke
				(width 0.1)
				(type default)
			)
			(layer "B.Fab")
		)
		(fp_line
			(start -0.12065 -0.3048)
			(end -0.67945 -0.3048)
			(stroke
				(width 0.1)
				(type default)
			)
			(layer "B.Fab")
		)
		(fp_line
			(start 0.12065 -0.305054)
			(end 0.12065 -0.2794)
			(stroke
				(width 0.1)
				(type default)
			)
			(layer "B.Fab")
		)
		(fp_line
			(start 0.67945 -0.305054)
			(end 0.12065 -0.305054)
			(stroke
				(width 0.1)
				(type default)
			)
			(layer "B.Fab")
		)
		(pad "1" smd circle
			(at 0.40005 0 90)
			(size 0 0)
			(layers "B.Cu" "B.Mask" "B.Paste")
			(net "PVNN_TERM_CPU1")
		)
		(pad "2" smd circle
			(at -0.40005 0 90)
			(size 0 0)
			(layers "B.Cu" "B.Mask" "B.Paste")
			(net "I3C_SPD_DDRABCD_CPU1_SDA")
		)
	)
	(footprint ""
		(layer "B.Cu")
		(at 477.30537 -90.156792 90)
		(property "Reference" "X47"
			(at -2.272792 -2.22504 270)
			(unlocked yes)
			(layer "B.SilkS")
			(effects
				(font
					(size 0.7874 0.5842)
					(thickness 0.1524)
				)
				(justify left mirror)
			)
		)
		(property "Value" ""
			(at 0 0 90)
			(layer "B.Fab")
			(effects
				(font
					(size 1.27 1.27)
				)
				(justify mirror)
			)
		)
		(property "Device Type" "TP_TDR_4P_FTS_TH-TP_TDR_4P_DIPA"
			(at -1.30175 1.27 0)
			(unlocked yes)
			(layer "B.Fab")
			(hide yes)
			(effects
				(font
					(size 0.635 0.4064)
					(thickness 0.1524)
				)
				(justify mirror)
			)
		)
		(property "User Part Number" "N_A"
			(at -1.30175 1.27 0)
			(unlocked yes)
			(layer "Cmts.User")
			(hide yes)
			(effects
				(font
					(size 0.635 0.4064)
					(thickness 0.1524)
				)
				(justify mirror)
			)
		)
		(duplicate_pad_numbers_are_jumpers no)
		(fp_line
			(start 0 -1.27)
			(end 0 -0.635)
			(stroke
				(width 0.1524)
				(type default)
			)
			(layer "B.SilkS")
		)
		(fp_line
			(start -2.54 -1.27)
			(end 0 -1.27)
			(stroke
				(width 0.1524)
				(type default)
			)
			(layer "B.SilkS")
		)
		(fp_line
			(start -2.54 -1.1303)
			(end -2.54 -1.27)
			(stroke
				(width 0.1524)
				(type default)
			)
			(layer "B.SilkS")
		)
		(fp_line
			(start 0 0.635)
			(end 0 1.905)
			(stroke
				(width 0.1524)
				(type default)
			)
			(layer "B.SilkS")
		)
		(fp_line
			(start -2.54 1.4097)
			(end -2.54 1.1303)
			(stroke
				(width 0.1524)
				(type default)
			)
			(layer "B.SilkS")
		)
		(fp_line
			(start 0 3.175)
			(end 0 3.81)
			(stroke
				(width 0.1524)
				(type default)
			)
			(layer "B.SilkS")
		)
		(fp_line
			(start 0 3.81)
			(end -2.54 3.81)
			(stroke
				(width 0.1524)
				(type default)
			)
			(layer "B.SilkS")
		)
		(fp_line
			(start -2.54 3.81)
			(end -2.54 3.6703)
			(stroke
				(width 0.1524)
				(type default)
			)
			(layer "B.SilkS")
		)
		(fp_poly
			(pts
				(xy 0.761746 0) (xy 2.285746 -0.762) (xy 2.285746 0.762)
			)
			(stroke
				(width 0)
				(type default)
			)
			(fill yes)
			(layer "B.SilkS")
		)
		(fp_line
			(start 0 -1.27)
			(end 0 3.81)
			(stroke
				(width 0.1)
				(type default)
			)
			(layer "B.Fab")
		)
		(fp_line
			(start -2.54 -1.27)
			(end 0 -1.27)
			(stroke
				(width 0.1)
				(type default)
			)
			(layer "B.Fab")
		)
		(fp_line
			(start 0 3.81)
			(end -2.54 3.81)
			(stroke
				(width 0.1)
				(type default)
			)
			(layer "B.Fab")
		)
		(fp_line
			(start -2.54 3.81)
			(end -2.54 -1.27)
			(stroke
				(width 0.1)
				(type default)
			)
			(layer "B.Fab")
		)
		(fp_poly
			(pts
				(xy 0.761746 0) (xy 2.285746 -0.762) (xy 2.285746 0.762)
			)
			(stroke
				(width 0)
				(type default)
			)
			(fill yes)
			(layer "B.Fab")
		)
		(pad "1" thru_hole circle
			(at 0 0 270)
			(size 1.0033 1.0033)
			(drill 0.249936)
			(layers "*.Cu" "*.Mask")
			(remove_unused_layers no)
			(net "TDR_DIFF_85_NECK_IN6_DN")
			(clearance 0.10795)
			(padstack
				(mode front_inner_back)
				(layer "Inner"
					(shape circle)
					(size 0.8001 0.8001)
					(clearance 0.1524)
				)
				(layer "B.Cu"
					(shape circle)
					(size 1.0033 1.0033)
					(thermal_gap 0.10795)
					(clearance 0.10795)
				)
			)
		)
		(pad "2" thru_hole circle
			(at -2.54 0 270)
			(size 1.9939 1.9939)
			(drill 0.249936)
			(layers "*.Cu" "*.Mask")
			(remove_unused_layers no)
			(net "T1_GND")
			(clearance 0.10795)
			(padstack
				(mode front_inner_back)
				(layer "Inner"
					(shape circle)
					(size 0.8001 0.8001)
					(clearance 0.1524)
				)
				(layer "B.Cu"
					(shape circle)
					(size 1.9939 1.9939)
					(thermal_gap 0.10795)
					(clearance 0.10795)
				)
			)
		)
		(pad "3" thru_hole circle
			(at -2.54 2.54 270)
			(size 1.9939 1.9939)
			(drill 0.249936)
			(layers "*.Cu" "*.Mask")
			(remove_unused_layers no)
			(net "T1_GND")
			(clearance 0.10795)
			(padstack
				(mode front_inner_back)
				(layer "Inner"
					(shape circle)
					(size 0.8001 0.8001)
					(clearance 0.1524)
				)
				(layer "B.Cu"
					(shape circle)
					(size 1.9939 1.9939)
					(thermal_gap 0.10795)
					(clearance 0.10795)
				)
			)
		)
		(pad "4" thru_hole circle
			(at 0 2.54 270)
			(size 1.0033 1.0033)
			(drill 0.249936)
			(layers "*.Cu" "*.Mask")
			(remove_unused_layers no)
			(net "TDR_DIFF_85_NECK_IN6_DP")
			(clearance 0.10795)
			(padstack
				(mode front_inner_back)
				(layer "Inner"
					(shape circle)
					(size 0.8001 0.8001)
					(clearance 0.1524)
				)
				(layer "B.Cu"
					(shape circle)
					(size 1.0033 1.0033)
					(thermal_gap 0.10795)
					(clearance 0.10795)
				)
			)
		)
	)
	(footprint ""
		(layer "B.Cu")
		(at 250.000516 -105.256584 90)
		(property "Reference" "R1483"
			(at 0 0 90)
			(layer "B.SilkS")
			(hide yes)
			(effects
				(font
					(size 1.27 1.27)
				)
				(justify mirror)
			)
		)
		(property "Value" ""
			(at 0 0 90)
			(layer "B.Fab")
			(effects
				(font
					(size 1.27 1.27)
				)
				(justify mirror)
			)
		)
		(duplicate_pad_numbers_are_jumpers no)
		(fp_line
			(start 0.7874 -0.4064)
			(end -0.7874 -0.4064)
			(stroke
				(width 0.1524)
				(type default)
			)
			(layer "B.SilkS")
		)
		(fp_line
			(start -0.7874 -0.4064)
			(end -0.7874 0.4064)
			(stroke
				(width 0.1524)
				(type default)
			)
			(layer "B.SilkS")
		)
		(fp_line
			(start 0.7874 0.4064)
			(end 0.7874 -0.4064)
			(stroke
				(width 0.1524)
				(type default)
			)
			(layer "B.SilkS")
		)
		(fp_line
			(start -0.7874 0.4064)
			(end 0.7874 0.4064)
			(stroke
				(width 0.1524)
				(type default)
			)
			(layer "B.SilkS")
		)
		(fp_line
			(start 0.67945 -0.305054)
			(end 0.12065 -0.305054)
			(stroke
				(width 0.1)
				(type default)
			)
			(layer "B.Fab")
		)
		(fp_line
			(start 0.12065 -0.305054)
			(end 0.12065 -0.2794)
			(stroke
				(width 0.1)
				(type default)
			)
			(layer "B.Fab")
		)
		(fp_line
			(start -0.12065 -0.3048)
			(end -0.67945 -0.3048)
			(stroke
				(width 0.1)
				(type default)
			)
			(layer "B.Fab")
		)
		(fp_line
			(start -0.67945 -0.3048)
			(end -0.67945 0.3048)
			(stroke
				(width 0.1)
				(type default)
			)
			(layer "B.Fab")
		)
		(fp_line
			(start 0.12065 -0.2794)
			(end -0.12065 -0.2794)
			(stroke
				(width 0.1)
				(type default)
			)
			(layer "B.Fab")
		)
		(fp_line
			(start -0.12065 -0.2794)
			(end -0.12065 -0.3048)
			(stroke
				(width 0.1)
				(type default)
			)
			(layer "B.Fab")
		)
		(fp_line
			(start 0.12065 0.2794)
			(end 0.12065 0.3048)
			(stroke
				(width 0.1)
				(type default)
			)
			(layer "B.Fab")
		)
		(fp_line
			(start -0.120396 0.2794)
			(end 0.12065 0.2794)
			(stroke
				(width 0.1)
				(type default)
			)
			(layer "B.Fab")
		)
		(fp_line
			(start 0.67945 0.3048)
			(end 0.67945 -0.305054)
			(stroke
				(width 0.1)
				(type default)
			)
			(layer "B.Fab")
		)
		(fp_line
			(start 0.12065 0.3048)
			(end 0.67945 0.3048)
			(stroke
				(width 0.1)
				(type default)
			)
			(layer "B.Fab")
		)
		(fp_line
			(start -0.120396 0.3048)
			(end -0.120396 0.2794)
			(stroke
				(width 0.1)
				(type default)
			)
			(layer "B.Fab")
		)
		(fp_line
			(start -0.67945 0.3048)
			(end -0.120396 0.3048)
			(stroke
				(width 0.1)
				(type default)
			)
			(layer "B.Fab")
		)
		(pad "1" smd circle
			(at 0.40005 0 270)
			(size 0 0)
			(layers "B.Cu" "B.Mask" "B.Paste")
			(net "P3V3_AUX")
		)
		(pad "2" smd circle
			(at -0.40005 0 270)
			(size 0 0)
			(layers "B.Cu" "B.Mask" "B.Paste")
			(net "FM_CK440Q_DEV_25M_EN")
		)
	)
)
